(kicad_pcb
	(version 20260206)
	(generator "pcbnew")
	(generator_version "10.0")
	(general
		(thickness 1.6)
		(legacy_teardrops no)
	)
	(paper "A4")
	(title_block
		(title "v1-chassis-manager — T6M_CM_d_v01_1031_1645.brd")
		(comment 1 "Open CloudServer (Microsoft) / footprints 1756-1765 of 2512")
	)
	(layers
		(0 "F.Cu" signal "TOP")
		(4 "In1.Cu" signal "GND1")
		(6 "In2.Cu" signal "IN1")
		(8 "In3.Cu" signal "VCC1")
		(10 "In4.Cu" signal "VCC2")
		(12 "In5.Cu" signal "GND2")
		(14 "In6.Cu" signal "IN2")
		(16 "In7.Cu" signal "IN3")
		(18 "In8.Cu" signal "GND3")
		(2 "B.Cu" signal "BOTTOM")
		(9 "F.Adhes" user "F.Adhesive")
		(11 "B.Adhes" user "B.Adhesive")
		(13 "F.Paste" user "Package Geometry/Pastemask Top")
		(15 "B.Paste" user "Package Geometry/Pastemask Bottom")
		(5 "F.SilkS" user "Ref Des/Silkscreen Top")
		(7 "B.SilkS" user "Ref Des/Silkscreen Bottom")
		(1 "F.Mask" user "Board Geometry/Soldermask Top")
		(3 "B.Mask" user "Board Geometry/Soldermask Bottom")
		(17 "Dwgs.User" user "User.Drawings")
		(19 "Cmts.User" user "User.Comments")
		(21 "Eco1.User" user "User.Eco1")
		(23 "Eco2.User" user "User.Eco2")
		(25 "Edge.Cuts" user "Board Geometry/Outline")
		(27 "Margin" user)
		(31 "F.CrtYd" user "Package Geometry/Place Bound Top")
		(29 "B.CrtYd" user "Package Geometry/Place Bound Bottom")
		(35 "F.Fab" user "Ref Des/Assembly Top")
		(33 "B.Fab" user "Ref Des/Assembly Bottom")
	)
	(footprint ""
		(layer "B.Cu")
		(at 64.139572 -70.608698 180)
		(property "Reference" "C105"
			(at 10.436352 -32.130492 0)
			(unlocked yes)
			(layer "B.SilkS")
			(effects
				(font
					(size 0.7874 0.5842)
					(thickness 0.1524)
				)
				(justify left mirror)
			)
		)
		(property "Value" ""
			(at 0 0 0)
			(layer "B.Fab")
			(effects
				(font
					(size 1.27 1.27)
				)
				(justify mirror)
			)
		)
		(duplicate_pad_numbers_are_jumpers no)
		(fp_line
			(start 0.7874 0.4064)
			(end 0.7874 -0.4064)
			(stroke
				(width 0.1524)
				(type default)
			)
			(layer "B.SilkS")
		)
		(fp_line
			(start 0.7874 -0.4064)
			(end -0.7874 -0.4064)
			(stroke
				(width 0.1524)
				(type default)
			)
			(layer "B.SilkS")
		)
		(fp_line
			(start 0 0.381)
			(end 0 -0.381)
			(stroke
				(width 0.1524)
				(type default)
			)
			(layer "B.SilkS")
		)
		(fp_line
			(start -0.7874 0.4064)
			(end 0.7874 0.4064)
			(stroke
				(width 0.1524)
				(type default)
			)
			(layer "B.SilkS")
		)
		(fp_line
			(start -0.7874 -0.4064)
			(end -0.7874 0.4064)
			(stroke
				(width 0.1524)
				(type default)
			)
			(layer "B.SilkS")
		)
		(fp_poly
			(pts
				(xy 0.5334 0.254) (xy 0.635 0.254) (xy 0.635 0.2286) (xy 0.635 -0.254) (xy 0.5334 -0.254) (xy 0.5334 -0.2794)
				(xy -0.5334 -0.2794) (xy -0.5334 -0.254) (xy -0.635 -0.254) (xy -0.635 0.254) (xy -0.5334 0.254)
				(xy -0.5334 0.2794) (xy 0.508 0.2794) (xy 0.5334 0.2794)
			)
			(stroke
				(width 0)
				(type default)
			)
			(fill no)
			(layer "B.CrtYd")
		)
		(pad "1" smd rect
			(at -0.40005 0)
			(size 0.4572 0.508)
			(layers "B.Cu" "B.Mask" "B.Paste")
			(net "P1V05_NODE1")
		)
		(pad "2" smd rect
			(at 0.40005 0)
			(size 0.4572 0.508)
			(layers "B.Cu" "B.Mask" "B.Paste")
			(net "GND")
		)
	)
	(footprint ""
		(layer "B.Cu")
		(at 63.339472 -138.557762 -90)
		(property "Reference" "C287"
			(at 56.057546 41.102534 270)
			(unlocked yes)
			(layer "B.SilkS")
			(effects
				(font
					(size 0.7874 0.5842)
					(thickness 0.1524)
				)
				(justify left mirror)
			)
		)
		(property "Value" ""
			(at 0 0 90)
			(layer "B.Fab")
			(effects
				(font
					(size 1.27 1.27)
				)
				(justify mirror)
			)
		)
		(duplicate_pad_numbers_are_jumpers no)
		(fp_line
			(start -0.7874 0.4064)
			(end 0.7874 0.4064)
			(stroke
				(width 0.1524)
				(type default)
			)
			(layer "B.SilkS")
		)
		(fp_line
			(start 0.7874 0.4064)
			(end 0.7874 -0.4064)
			(stroke
				(width 0.1524)
				(type default)
			)
			(layer "B.SilkS")
		)
		(fp_line
			(start 0 0.381)
			(end 0 -0.381)
			(stroke
				(width 0.1524)
				(type default)
			)
			(layer "B.SilkS")
		)
		(fp_line
			(start -0.7874 -0.4064)
			(end -0.7874 0.4064)
			(stroke
				(width 0.1524)
				(type default)
			)
			(layer "B.SilkS")
		)
		(fp_line
			(start 0.7874 -0.4064)
			(end -0.7874 -0.4064)
			(stroke
				(width 0.1524)
				(type default)
			)
			(layer "B.SilkS")
		)
		(fp_poly
			(pts
				(xy 0.5334 0.254) (xy 0.635 0.254) (xy 0.635 0.2286) (xy 0.635 -0.254) (xy 0.5334 -0.254) (xy 0.5334 -0.2794)
				(xy -0.5334 -0.2794) (xy -0.5334 -0.254) (xy -0.635 -0.254) (xy -0.635 0.254) (xy -0.5334 0.254)
				(xy -0.5334 0.2794) (xy 0.508 0.2794) (xy 0.5334 0.2794)
			)
			(stroke
				(width 0)
				(type default)
			)
			(fill no)
			(layer "B.CrtYd")
		)
		(pad "1" smd rect
			(at -0.40005 0 90)
			(size 0.4572 0.508)
			(layers "B.Cu" "B.Mask" "B.Paste")
			(net "P1V26_BMC_NODE1")
		)
		(pad "2" smd rect
			(at 0.40005 0 90)
			(size 0.4572 0.508)
			(layers "B.Cu" "B.Mask" "B.Paste")
			(net "GND")
		)
	)
	(footprint ""
		(layer "B.Cu")
		(at 134.934452 -113.975642 90)
		(property "Reference" "C196"
			(at 0.933196 -0.29972 270)
			(unlocked yes)
			(layer "B.SilkS")
			(effects
				(font
					(size 0.7874 0.5842)
					(thickness 0.1524)
				)
				(justify left mirror)
			)
		)
		(property "Value" ""
			(at 0 0 90)
			(layer "B.Fab")
			(effects
				(font
					(size 1.27 1.27)
				)
				(justify mirror)
			)
		)
		(duplicate_pad_numbers_are_jumpers no)
		(fp_line
			(start 0.7874 -0.4064)
			(end -0.7874 -0.4064)
			(stroke
				(width 0.1524)
				(type default)
			)
			(layer "B.SilkS")
		)
		(fp_line
			(start -0.7874 -0.4064)
			(end -0.7874 0.4064)
			(stroke
				(width 0.1524)
				(type default)
			)
			(layer "B.SilkS")
		)
		(fp_line
			(start 0 0.381)
			(end 0 -0.381)
			(stroke
				(width 0.1524)
				(type default)
			)
			(layer "B.SilkS")
		)
		(fp_line
			(start 0.7874 0.4064)
			(end 0.7874 -0.4064)
			(stroke
				(width 0.1524)
				(type default)
			)
			(layer "B.SilkS")
		)
		(fp_line
			(start -0.7874 0.4064)
			(end 0.7874 0.4064)
			(stroke
				(width 0.1524)
				(type default)
			)
			(layer "B.SilkS")
		)
		(fp_poly
			(pts
				(xy 0.5334 0.254) (xy 0.635 0.254) (xy 0.635 0.2286) (xy 0.635 -0.254) (xy 0.5334 -0.254) (xy 0.5334 -0.2794)
				(xy -0.5334 -0.2794) (xy -0.5334 -0.254) (xy -0.635 -0.254) (xy -0.635 0.254) (xy -0.5334 0.254)
				(xy -0.5334 0.2794) (xy 0.508 0.2794) (xy 0.5334 0.2794)
			)
			(stroke
				(width 0)
				(type default)
			)
			(fill no)
			(layer "B.CrtYd")
		)
		(pad "1" smd rect
			(at -0.40005 0 270)
			(size 0.4572 0.508)
			(layers "B.Cu" "B.Mask" "B.Paste")
			(net "P3V3_CLK_NODE1")
		)
		(pad "2" smd rect
			(at 0.40005 0 270)
			(size 0.4572 0.508)
			(layers "B.Cu" "B.Mask" "B.Paste")
			(net "GND")
		)
	)
	(footprint ""
		(layer "B.Cu")
		(at 52.09667 -81.4832)
		(property "Reference" "R200"
			(at -13.00607 32.10687 0)
			(unlocked yes)
			(layer "B.SilkS")
			(effects
				(font
					(size 0.7874 0.5842)
					(thickness 0.1524)
				)
				(justify left mirror)
			)
		)
		(property "Value" ""
			(at 0 0 0)
			(layer "B.Fab")
			(effects
				(font
					(size 1.27 1.27)
				)
				(justify mirror)
			)
		)
		(duplicate_pad_numbers_are_jumpers no)
		(fp_line
			(start -0.7874 -0.4064)
			(end -0.7874 0.4064)
			(stroke
				(width 0.1524)
				(type default)
			)
			(layer "B.SilkS")
		)
		(fp_line
			(start -0.7874 0.4064)
			(end 0.7874 0.4064)
			(stroke
				(width 0.1524)
				(type default)
			)
			(layer "B.SilkS")
		)
		(fp_line
			(start 0.7874 -0.4064)
			(end -0.7874 -0.4064)
			(stroke
				(width 0.1524)
				(type default)
			)
			(layer "B.SilkS")
		)
		(fp_line
			(start 0.7874 0.4064)
			(end 0.7874 -0.4064)
			(stroke
				(width 0.1524)
				(type default)
			)
			(layer "B.SilkS")
		)
		(fp_poly
			(pts
				(xy 0.508 0.2794) (xy 0.508 0.2286) (xy 0.635 0.2286) (xy 0.635 -0.254) (xy 0.5334 -0.254) (xy 0.5334 -0.2794)
				(xy -0.5334 -0.2794) (xy -0.5334 -0.254) (xy -0.635 -0.254) (xy -0.635 0.254) (xy -0.5334 0.254)
				(xy -0.5334 0.2794)
			)
			(stroke
				(width 0)
				(type default)
			)
			(fill no)
			(layer "B.CrtYd")
		)
		(pad "1" smd rect
			(at -0.40005 0 180)
			(size 0.4572 0.508)
			(layers "B.Cu" "B.Mask" "B.Paste")
			(net "A_CPU_NODE1_SOC_THERMREFNPAD")
		)
		(pad "2" smd rect
			(at 0.40005 0 180)
			(size 0.4572 0.508)
			(layers "B.Cu" "B.Mask" "B.Paste")
			(net "P1V05_NODE1")
		)
	)
	(footprint ""
		(layer "B.Cu")
		(at 65.357502 -29.865828)
		(property "Reference" "C172"
			(at -3.013202 -0.287528 0)
			(unlocked yes)
			(layer "B.SilkS")
			(effects
				(font
					(size 0.7874 0.5842)
					(thickness 0.1524)
				)
				(justify mirror)
			)
		)
		(property "Value" ""
			(at 0 0 0)
			(layer "B.Fab")
			(effects
				(font
					(size 1.27 1.27)
				)
				(justify mirror)
			)
		)
		(duplicate_pad_numbers_are_jumpers no)
		(fp_line
			(start -1.2954 -0.5842)
			(end -1.2954 0.5842)
			(stroke
				(width 0.1524)
				(type default)
			)
			(layer "B.SilkS")
		)
		(fp_line
			(start -1.2954 0.5842)
			(end 1.2954 0.5842)
			(stroke
				(width 0.1524)
				(type default)
			)
			(layer "B.SilkS")
		)
		(fp_line
			(start 0 -0.5842)
			(end 0 0.5842)
			(stroke
				(width 0.1524)
				(type default)
			)
			(layer "B.SilkS")
		)
		(fp_line
			(start 1.2954 -0.5842)
			(end -1.2954 -0.5842)
			(stroke
				(width 0.1524)
				(type default)
			)
			(layer "B.SilkS")
		)
		(fp_line
			(start 1.2954 0.5842)
			(end 1.2954 -0.5842)
			(stroke
				(width 0.1524)
				(type default)
			)
			(layer "B.SilkS")
		)
		(fp_poly
			(pts
				(xy -0.8636 -0.4572) (xy -0.8636 -0.3556) (xy -1.143 -0.3556) (xy -1.143 0.3556) (xy -0.8636 0.3556)
				(xy -0.8636 0.4572) (xy 0.8636 0.4572) (xy 0.8636 0.3556) (xy 1.143 0.3556) (xy 1.143 -0.3556) (xy 0.8636 -0.3556)
				(xy 0.8636 -0.4572)
			)
			(stroke
				(width 0)
				(type default)
			)
			(fill no)
			(layer "B.CrtYd")
		)
		(fp_line
			(start -0.884936 -0.504952)
			(end -0.884936 0.504952)
			(stroke
				(width 0.1)
				(type default)
			)
			(layer "B.Fab")
		)
		(fp_line
			(start -0.884936 0.504952)
			(end 0.884936 0.504952)
			(stroke
				(width 0.1)
				(type default)
			)
			(layer "B.Fab")
		)
		(fp_line
			(start 0.884936 -0.504952)
			(end -0.884936 -0.504952)
			(stroke
				(width 0.1)
				(type default)
			)
			(layer "B.Fab")
		)
		(fp_line
			(start 0.884936 0.504952)
			(end 0.884936 -0.504952)
			(stroke
				(width 0.1)
				(type default)
			)
			(layer "B.Fab")
		)
		(pad "1" smd rect
			(at -0.7366 0 90)
			(size 0.7112 0.8128)
			(layers "B.Cu" "B.Mask" "B.Paste")
			(net "PV_VDDR_NODE1")
		)
		(pad "2" smd rect
			(at 0.7366 0 90)
			(size 0.7112 0.8128)
			(layers "B.Cu" "B.Mask" "B.Paste")
			(net "GND")
		)
	)
	(footprint ""
		(layer "B.Cu")
		(at 94.211394 -188.838586 180)
		(property "Reference" "C702"
			(at -1.315466 6.008116 0)
			(unlocked yes)
			(layer "B.SilkS")
			(effects
				(font
					(size 0.7874 0.5842)
					(thickness 0.1524)
				)
				(justify left mirror)
			)
		)
		(property "Value" ""
			(at 0 0 0)
			(layer "B.Fab")
			(effects
				(font
					(size 1.27 1.27)
				)
				(justify mirror)
			)
		)
		(duplicate_pad_numbers_are_jumpers no)
		(fp_line
			(start 0.7874 0.4064)
			(end 0.7874 -0.4064)
			(stroke
				(width 0.1524)
				(type default)
			)
			(layer "B.SilkS")
		)
		(fp_line
			(start 0.7874 -0.4064)
			(end -0.7874 -0.4064)
			(stroke
				(width 0.1524)
				(type default)
			)
			(layer "B.SilkS")
		)
		(fp_line
			(start 0 0.381)
			(end 0 -0.381)
			(stroke
				(width 0.1524)
				(type default)
			)
			(layer "B.SilkS")
		)
		(fp_line
			(start -0.7874 0.4064)
			(end 0.7874 0.4064)
			(stroke
				(width 0.1524)
				(type default)
			)
			(layer "B.SilkS")
		)
		(fp_line
			(start -0.7874 -0.4064)
			(end -0.7874 0.4064)
			(stroke
				(width 0.1524)
				(type default)
			)
			(layer "B.SilkS")
		)
		(fp_poly
			(pts
				(xy 0.5334 0.254) (xy 0.635 0.254) (xy 0.635 0.2286) (xy 0.635 -0.254) (xy 0.5334 -0.254) (xy 0.5334 -0.2794)
				(xy -0.5334 -0.2794) (xy -0.5334 -0.254) (xy -0.635 -0.254) (xy -0.635 0.254) (xy -0.5334 0.254)
				(xy -0.5334 0.2794) (xy 0.508 0.2794) (xy 0.5334 0.2794)
			)
			(stroke
				(width 0)
				(type default)
			)
			(fill no)
			(layer "B.CrtYd")
		)
		(pad "1" smd rect
			(at -0.40005 0)
			(size 0.4572 0.508)
			(layers "B.Cu" "B.Mask" "B.Paste")
			(net "UART_T6_NODE2_RXD")
		)
		(pad "2" smd rect
			(at 0.40005 0)
			(size 0.4572 0.508)
			(layers "B.Cu" "B.Mask" "B.Paste")
			(net "GND")
		)
	)
	(footprint ""
		(layer "B.Cu")
		(at 88.721438 -79.781908)
		(property "Reference" "R115"
			(at -1.91516 9.518142 0)
			(unlocked yes)
			(layer "B.SilkS")
			(effects
				(font
					(size 0.7874 0.5842)
					(thickness 0.1524)
				)
				(justify left mirror)
			)
		)
		(property "Value" ""
			(at 0 0 0)
			(layer "B.Fab")
			(effects
				(font
					(size 1.27 1.27)
				)
				(justify mirror)
			)
		)
		(duplicate_pad_numbers_are_jumpers no)
		(fp_line
			(start -0.7874 -0.4064)
			(end -0.7874 0.4064)
			(stroke
				(width 0.1524)
				(type default)
			)
			(layer "B.SilkS")
		)
		(fp_line
			(start -0.7874 0.4064)
			(end 0.7874 0.4064)
			(stroke
				(width 0.1524)
				(type default)
			)
			(layer "B.SilkS")
		)
		(fp_line
			(start 0.7874 -0.4064)
			(end -0.7874 -0.4064)
			(stroke
				(width 0.1524)
				(type default)
			)
			(layer "B.SilkS")
		)
		(fp_line
			(start 0.7874 0.4064)
			(end 0.7874 -0.4064)
			(stroke
				(width 0.1524)
				(type default)
			)
			(layer "B.SilkS")
		)
		(fp_poly
			(pts
				(xy 0.508 0.2794) (xy 0.508 0.2286) (xy 0.635 0.2286) (xy 0.635 -0.254) (xy 0.5334 -0.254) (xy 0.5334 -0.2794)
				(xy -0.5334 -0.2794) (xy -0.5334 -0.254) (xy -0.635 -0.254) (xy -0.635 0.254) (xy -0.5334 0.254)
				(xy -0.5334 0.2794)
			)
			(stroke
				(width 0)
				(type default)
			)
			(fill no)
			(layer "B.CrtYd")
		)
		(pad "1" smd rect
			(at -0.40005 0 180)
			(size 0.4572 0.508)
			(layers "B.Cu" "B.Mask" "B.Paste")
			(net "H_CPU_NODE1_PROCHOT_L")
		)
		(pad "2" smd rect
			(at 0.40005 0 180)
			(size 0.4572 0.508)
			(layers "B.Cu" "B.Mask" "B.Paste")
			(net "P1V05_NODE1")
		)
	)
	(footprint ""
		(layer "B.Cu")
		(at 40.654732 -94.40037 -90)
		(property "Reference" "C26"
			(at 4.703318 4.59994 270)
			(unlocked yes)
			(layer "B.SilkS")
			(effects
				(font
					(size 0.7874 0.5842)
					(thickness 0.1524)
				)
				(justify left mirror)
			)
		)
		(property "Value" ""
			(at 0 0 90)
			(layer "B.Fab")
			(effects
				(font
					(size 1.27 1.27)
				)
				(justify mirror)
			)
		)
		(duplicate_pad_numbers_are_jumpers no)
		(fp_line
			(start -0.7874 0.4064)
			(end 0.7874 0.4064)
			(stroke
				(width 0.1524)
				(type default)
			)
			(layer "B.SilkS")
		)
		(fp_line
			(start 0.7874 0.4064)
			(end 0.7874 -0.4064)
			(stroke
				(width 0.1524)
				(type default)
			)
			(layer "B.SilkS")
		)
		(fp_line
			(start 0 0.381)
			(end 0 -0.381)
			(stroke
				(width 0.1524)
				(type default)
			)
			(layer "B.SilkS")
		)
		(fp_line
			(start -0.7874 -0.4064)
			(end -0.7874 0.4064)
			(stroke
				(width 0.1524)
				(type default)
			)
			(layer "B.SilkS")
		)
		(fp_line
			(start 0.7874 -0.4064)
			(end -0.7874 -0.4064)
			(stroke
				(width 0.1524)
				(type default)
			)
			(layer "B.SilkS")
		)
		(fp_poly
			(pts
				(xy 0.5334 0.254) (xy 0.635 0.254) (xy 0.635 0.2286) (xy 0.635 -0.254) (xy 0.5334 -0.254) (xy 0.5334 -0.2794)
				(xy -0.5334 -0.2794) (xy -0.5334 -0.254) (xy -0.635 -0.254) (xy -0.635 0.254) (xy -0.5334 0.254)
				(xy -0.5334 0.2794) (xy 0.508 0.2794) (xy 0.5334 0.2794)
			)
			(stroke
				(width 0)
				(type default)
			)
			(fill no)
			(layer "B.CrtYd")
		)
		(pad "1" smd rect
			(at -0.40005 0 90)
			(size 0.4572 0.508)
			(layers "B.Cu" "B.Mask" "B.Paste")
			(net "GND")
		)
		(pad "2" smd rect
			(at 0.40005 0 90)
			(size 0.4572 0.508)
			(layers "B.Cu" "B.Mask" "B.Paste")
			(net "SMB_CPU_NODE1_XDP_CLK_R")
		)
	)
	(footprint ""
		(layer "B.Cu")
		(at 122.0978 -44.732702)
		(property "Reference" "R182"
			(at -2.808732 -0.016256 0)
			(unlocked yes)
			(layer "B.SilkS")
			(effects
				(font
					(size 0.7874 0.5842)
					(thickness 0.1524)
				)
				(justify left mirror)
			)
		)
		(property "Value" ""
			(at 0 0 0)
			(layer "B.Fab")
			(effects
				(font
					(size 1.27 1.27)
				)
				(justify mirror)
			)
		)
		(duplicate_pad_numbers_are_jumpers no)
		(fp_line
			(start -0.7874 -0.4064)
			(end -0.7874 0.4064)
			(stroke
				(width 0.1524)
				(type default)
			)
			(layer "B.SilkS")
		)
		(fp_line
			(start -0.7874 0.4064)
			(end 0.7874 0.4064)
			(stroke
				(width 0.1524)
				(type default)
			)
			(layer "B.SilkS")
		)
		(fp_line
			(start 0.7874 -0.4064)
			(end -0.7874 -0.4064)
			(stroke
				(width 0.1524)
				(type default)
			)
			(layer "B.SilkS")
		)
		(fp_line
			(start 0.7874 0.4064)
			(end 0.7874 -0.4064)
			(stroke
				(width 0.1524)
				(type default)
			)
			(layer "B.SilkS")
		)
		(fp_poly
			(pts
				(xy 0.508 0.2794) (xy 0.508 0.2286) (xy 0.635 0.2286) (xy 0.635 -0.254) (xy 0.5334 -0.254) (xy 0.5334 -0.2794)
				(xy -0.5334 -0.2794) (xy -0.5334 -0.254) (xy -0.635 -0.254) (xy -0.635 0.254) (xy -0.5334 0.254)
				(xy -0.5334 0.2794)
			)
			(stroke
				(width 0)
				(type default)
			)
			(fill no)
			(layer "B.CrtYd")
		)
		(pad "1" smd rect
			(at -0.40005 0 180)
			(size 0.4572 0.508)
			(layers "B.Cu" "B.Mask" "B.Paste")
			(net "LPC_CPU_NODE1_LAD0")
		)
		(pad "2" smd rect
			(at 0.40005 0 180)
			(size 0.4572 0.508)
			(layers "B.Cu" "B.Mask" "B.Paste")
			(net "LPC_CPU_NODE1_LAD0_SIO")
		)
	)
	(footprint ""
		(layer "B.Cu")
		(at 88.77935 -75.717654 180)
		(property "Reference" "R167"
			(at 1.91516 -9.834118 0)
			(unlocked yes)
			(layer "B.SilkS")
			(effects
				(font
					(size 0.7874 0.5842)
					(thickness 0.1524)
				)
				(justify left mirror)
			)
		)
		(property "Value" ""
			(at 0 0 0)
			(layer "B.Fab")
			(effects
				(font
					(size 1.27 1.27)
				)
				(justify mirror)
			)
		)
		(duplicate_pad_numbers_are_jumpers no)
		(fp_line
			(start 0.7874 0.4064)
			(end 0.7874 -0.4064)
			(stroke
				(width 0.1524)
				(type default)
			)
			(layer "B.SilkS")
		)
		(fp_line
			(start 0.7874 -0.4064)
			(end -0.7874 -0.4064)
			(stroke
				(width 0.1524)
				(type default)
			)
			(layer "B.SilkS")
		)
		(fp_line
			(start -0.7874 0.4064)
			(end 0.7874 0.4064)
			(stroke
				(width 0.1524)
				(type default)
			)
			(layer "B.SilkS")
		)
		(fp_line
			(start -0.7874 -0.4064)
			(end -0.7874 0.4064)
			(stroke
				(width 0.1524)
				(type default)
			)
			(layer "B.SilkS")
		)
		(fp_poly
			(pts
				(xy 0.508 0.2794) (xy 0.508 0.2286) (xy 0.635 0.2286) (xy 0.635 -0.254) (xy 0.5334 -0.254) (xy 0.5334 -0.2794)
				(xy -0.5334 -0.2794) (xy -0.5334 -0.254) (xy -0.635 -0.254) (xy -0.635 0.254) (xy -0.5334 0.254)
				(xy -0.5334 0.2794)
			)
			(stroke
				(width 0)
				(type default)
			)
			(fill no)
			(layer "B.CrtYd")
		)
		(pad "1" smd rect
			(at -0.40005 0)
			(size 0.4572 0.508)
			(layers "B.Cu" "B.Mask" "B.Paste")
			(net "GND")
		)
		(pad "2" smd rect
			(at 0.40005 0)
			(size 0.4572 0.508)
			(layers "B.Cu" "B.Mask" "B.Paste")
			(net "PD_CPU_NODE1_MEM_SPEED1")
		)
	)
)
